(kicad_pcb
	(version 20260206)
	(generator "pcbnew")
	(generator_version "10.0")
	(general
		(thickness 1.6)
		(legacy_teardrops no)
	)
	(paper "A4")
	(title_block
		(title "03242023_DA0F0TMBIJ0_F0T_Motherboard_J_brd_V01_OCP.brd")
		(comment 1 "Grand Teton / footprints 3717-3722 of 6105")
	)
	(layers
		(0 "F.Cu" signal "TOP")
		(4 "In1.Cu" signal "GND")
		(6 "In2.Cu" signal "IN1")
		(8 "In3.Cu" signal "GND1")
		(10 "In4.Cu" signal "IN2")
		(12 "In5.Cu" signal "GND2")
		(14 "In6.Cu" signal "IN3")
		(16 "In7.Cu" signal "GND3")
		(18 "In8.Cu" signal "VCC")
		(20 "In9.Cu" signal "VCC1")
		(22 "In10.Cu" signal "GND4")
		(24 "In11.Cu" signal "IN4")
		(26 "In12.Cu" signal "GND5")
		(28 "In13.Cu" signal "IN5")
		(30 "In14.Cu" signal "GND6")
		(32 "In15.Cu" signal "IN6")
		(34 "In16.Cu" signal "GND7")
		(2 "B.Cu" signal "BOTTOM")
		(9 "F.Adhes" user "F.Adhesive")
		(11 "B.Adhes" user "B.Adhesive")
		(13 "F.Paste" user "Package Geometry/Pastemask Top")
		(15 "B.Paste" user "Package Geometry/Pastemask Bottom")
		(5 "F.SilkS" user "Ref Des/Silkscreen Top")
		(7 "B.SilkS" user "Ref Des/Silkscreen Bottom")
		(1 "F.Mask" user "Board Geometry/Soldermask Top")
		(3 "B.Mask" user "Board Geometry/Soldermask Bottom")
		(17 "Dwgs.User" user "User.Drawings")
		(19 "Cmts.User" user "User.Comments")
		(21 "Eco1.User" user "User.Eco1")
		(23 "Eco2.User" user "User.Eco2")
		(25 "Edge.Cuts" user "Board Geometry/Outline")
		(27 "Margin" user)
		(31 "F.CrtYd" user "Package Geometry/Place Bound Top")
		(29 "B.CrtYd" user "Package Geometry/Place Bound Bottom")
		(35 "F.Fab" user "Ref Des/Assembly Top")
		(33 "B.Fab" user "Ref Des/Assembly Bottom")
	)
	(footprint ""
		(layer "F.Cu")
		(at 73.496678 -29.845762 90)
		(property "Reference" "PC2165"
			(at 0 0 90)
			(layer "F.SilkS")
			(hide yes)
			(effects
				(font
					(size 1.27 1.27)
				)
			)
		)
		(property "Value" ""
			(at 0 0 90)
			(layer "F.Fab")
			(effects
				(font
					(size 1.27 1.27)
				)
			)
		)
		(duplicate_pad_numbers_are_jumpers no)
		(fp_line
			(start 0.7874 -0.4064)
			(end 0.7874 0.4064)
			(stroke
				(width 0.1524)
				(type default)
			)
			(layer "F.SilkS")
		)
		(fp_line
			(start -0.7874 -0.4064)
			(end 0.7874 -0.4064)
			(stroke
				(width 0.1524)
				(type default)
			)
			(layer "F.SilkS")
		)
		(fp_line
			(start 0.7874 0.4064)
			(end -0.7874 0.4064)
			(stroke
				(width 0.1524)
				(type default)
			)
			(layer "F.SilkS")
		)
		(fp_line
			(start -0.7874 0.4064)
			(end -0.7874 -0.4064)
			(stroke
				(width 0.1524)
				(type default)
			)
			(layer "F.SilkS")
		)
		(fp_line
			(start -0.12065 -0.305054)
			(end -0.12065 -0.2794)
			(stroke
				(width 0.1)
				(type default)
			)
			(layer "F.Fab")
		)
		(fp_line
			(start -0.67945 -0.305054)
			(end -0.12065 -0.305054)
			(stroke
				(width 0.1)
				(type default)
			)
			(layer "F.Fab")
		)
		(fp_line
			(start 0.67945 -0.3048)
			(end 0.67945 0.3048)
			(stroke
				(width 0.1)
				(type default)
			)
			(layer "F.Fab")
		)
		(fp_line
			(start 0.12065 -0.3048)
			(end 0.67945 -0.3048)
			(stroke
				(width 0.1)
				(type default)
			)
			(layer "F.Fab")
		)
		(fp_line
			(start 0.12065 -0.2794)
			(end 0.12065 -0.3048)
			(stroke
				(width 0.1)
				(type default)
			)
			(layer "F.Fab")
		)
		(fp_line
			(start -0.12065 -0.2794)
			(end 0.12065 -0.2794)
			(stroke
				(width 0.1)
				(type default)
			)
			(layer "F.Fab")
		)
		(fp_line
			(start 0.120396 0.2794)
			(end -0.12065 0.2794)
			(stroke
				(width 0.1)
				(type default)
			)
			(layer "F.Fab")
		)
		(fp_line
			(start -0.12065 0.2794)
			(end -0.12065 0.3048)
			(stroke
				(width 0.1)
				(type default)
			)
			(layer "F.Fab")
		)
		(fp_line
			(start 0.67945 0.3048)
			(end 0.120396 0.3048)
			(stroke
				(width 0.1)
				(type default)
			)
			(layer "F.Fab")
		)
		(fp_line
			(start 0.120396 0.3048)
			(end 0.120396 0.2794)
			(stroke
				(width 0.1)
				(type default)
			)
			(layer "F.Fab")
		)
		(fp_line
			(start -0.12065 0.3048)
			(end -0.67945 0.3048)
			(stroke
				(width 0.1)
				(type default)
			)
			(layer "F.Fab")
		)
		(fp_line
			(start -0.67945 0.3048)
			(end -0.67945 -0.305054)
			(stroke
				(width 0.1)
				(type default)
			)
			(layer "F.Fab")
		)
		(pad "1" smd circle
			(at -0.40005 0 90)
			(size 0 0)
			(layers "F.Cu" "F.Mask" "F.Paste")
			(net "P12V_AUX")
		)
		(pad "2" smd circle
			(at 0.40005 0 90)
			(size 0 0)
			(layers "F.Cu" "F.Mask" "F.Paste")
			(net "GND")
		)
	)
	(footprint ""
		(layer "F.Cu")
		(at 249.81535 -73.290684)
		(property "Reference" "PL110"
			(at -2.3876 -2.969768 0)
			(unlocked yes)
			(layer "F.SilkS")
			(effects
				(font
					(size 0.7874 0.5842)
					(thickness 0.1524)
				)
				(justify left)
			)
		)
		(property "Value" ""
			(at 0 0 0)
			(layer "F.Fab")
			(effects
				(font
					(size 1.27 1.27)
				)
			)
		)
		(duplicate_pad_numbers_are_jumpers no)
		(fp_line
			(start -2.249932 -2.249932)
			(end 2.249932 -2.249932)
			(stroke
				(width 0.1524)
				(type default)
			)
			(layer "F.SilkS")
		)
		(fp_line
			(start -2.249932 -1.3843)
			(end -2.249932 -2.249932)
			(stroke
				(width 0.1524)
				(type default)
			)
			(layer "F.SilkS")
		)
		(fp_line
			(start -2.249932 2.249932)
			(end -2.249932 1.3843)
			(stroke
				(width 0.1524)
				(type default)
			)
			(layer "F.SilkS")
		)
		(fp_line
			(start 2.249932 -2.249932)
			(end 2.249932 -1.3843)
			(stroke
				(width 0.1524)
				(type default)
			)
			(layer "F.SilkS")
		)
		(fp_line
			(start 2.249932 1.3843)
			(end 2.249932 2.249932)
			(stroke
				(width 0.1524)
				(type default)
			)
			(layer "F.SilkS")
		)
		(fp_line
			(start 2.249932 2.249932)
			(end -2.249932 2.249932)
			(stroke
				(width 0.1524)
				(type default)
			)
			(layer "F.SilkS")
		)
		(fp_line
			(start -2.249932 -2.249932)
			(end 2.249932 -2.249932)
			(stroke
				(width 0.1)
				(type default)
			)
			(layer "F.Fab")
		)
		(fp_line
			(start -2.249932 2.249932)
			(end -2.249932 -2.249932)
			(stroke
				(width 0.1)
				(type default)
			)
			(layer "F.Fab")
		)
		(fp_line
			(start 2.249932 -2.249932)
			(end 2.249932 2.249932)
			(stroke
				(width 0.1)
				(type default)
			)
			(layer "F.Fab")
		)
		(fp_line
			(start 2.249932 2.249932)
			(end -2.249932 2.249932)
			(stroke
				(width 0.1)
				(type default)
			)
			(layer "F.Fab")
		)
		(pad "1" smd rect
			(at -1.82499 0)
			(size 1.0668 2.5146)
			(layers "F.Cu" "F.Mask" "F.Paste")
			(net "P12V_AUX")
		)
		(pad "2" smd rect
			(at 1.82499 0)
			(size 1.0668 2.5146)
			(layers "F.Cu" "F.Mask" "F.Paste")
			(net "SW_P12V_AUX_P1V05_PCH_AUX_FLT")
		)
	)
	(footprint ""
		(layer "F.Cu")
		(at 24.050752 -404.842218 180)
		(property "Reference" "C1974"
			(at 0 0 180)
			(layer "F.SilkS")
			(hide yes)
			(effects
				(font
					(size 1.27 1.27)
				)
			)
		)
		(property "Value" ""
			(at 0 0 180)
			(layer "F.Fab")
			(effects
				(font
					(size 1.27 1.27)
				)
			)
		)
		(duplicate_pad_numbers_are_jumpers no)
		(fp_line
			(start 0.7874 0.4064)
			(end -0.7874 0.4064)
			(stroke
				(width 0.1524)
				(type default)
			)
			(layer "F.SilkS")
		)
		(fp_line
			(start 0.7874 -0.4064)
			(end 0.7874 0.4064)
			(stroke
				(width 0.1524)
				(type default)
			)
			(layer "F.SilkS")
		)
		(fp_line
			(start -0.7874 0.4064)
			(end -0.7874 -0.4064)
			(stroke
				(width 0.1524)
				(type default)
			)
			(layer "F.SilkS")
		)
		(fp_line
			(start -0.7874 -0.4064)
			(end 0.7874 -0.4064)
			(stroke
				(width 0.1524)
				(type default)
			)
			(layer "F.SilkS")
		)
		(fp_line
			(start 0.67945 0.3048)
			(end 0.120396 0.3048)
			(stroke
				(width 0.1)
				(type default)
			)
			(layer "F.Fab")
		)
		(fp_line
			(start 0.67945 -0.3048)
			(end 0.67945 0.3048)
			(stroke
				(width 0.1)
				(type default)
			)
			(layer "F.Fab")
		)
		(fp_line
			(start 0.12065 -0.2794)
			(end 0.12065 -0.3048)
			(stroke
				(width 0.1)
				(type default)
			)
			(layer "F.Fab")
		)
		(fp_line
			(start 0.12065 -0.3048)
			(end 0.67945 -0.3048)
			(stroke
				(width 0.1)
				(type default)
			)
			(layer "F.Fab")
		)
		(fp_line
			(start 0.120396 0.3048)
			(end 0.120396 0.2794)
			(stroke
				(width 0.1)
				(type default)
			)
			(layer "F.Fab")
		)
		(fp_line
			(start 0.120396 0.2794)
			(end -0.12065 0.2794)
			(stroke
				(width 0.1)
				(type default)
			)
			(layer "F.Fab")
		)
		(fp_line
			(start -0.12065 0.3048)
			(end -0.67945 0.3048)
			(stroke
				(width 0.1)
				(type default)
			)
			(layer "F.Fab")
		)
		(fp_line
			(start -0.12065 0.2794)
			(end -0.12065 0.3048)
			(stroke
				(width 0.1)
				(type default)
			)
			(layer "F.Fab")
		)
		(fp_line
			(start -0.12065 -0.2794)
			(end 0.12065 -0.2794)
			(stroke
				(width 0.1)
				(type default)
			)
			(layer "F.Fab")
		)
		(fp_line
			(start -0.12065 -0.305054)
			(end -0.12065 -0.2794)
			(stroke
				(width 0.1)
				(type default)
			)
			(layer "F.Fab")
		)
		(fp_line
			(start -0.67945 0.3048)
			(end -0.67945 -0.305054)
			(stroke
				(width 0.1)
				(type default)
			)
			(layer "F.Fab")
		)
		(fp_line
			(start -0.67945 -0.305054)
			(end -0.12065 -0.305054)
			(stroke
				(width 0.1)
				(type default)
			)
			(layer "F.Fab")
		)
		(pad "1" smd circle
			(at -0.40005 0 180)
			(size 0 0)
			(layers "F.Cu" "F.Mask" "F.Paste")
			(net "GPU_FPGA_THERM_OVERT_ISO_N")
		)
		(pad "2" smd circle
			(at 0.40005 0 180)
			(size 0 0)
			(layers "F.Cu" "F.Mask" "F.Paste")
			(net "GND")
		)
	)
	(footprint ""
		(layer "F.Cu")
		(at 427.452028 -159.516318)
		(property "Reference" "PC208"
			(at 0 0 0)
			(layer "F.SilkS")
			(hide yes)
			(effects
				(font
					(size 1.27 1.27)
				)
			)
		)
		(property "Value" ""
			(at 0 0 0)
			(layer "F.Fab")
			(effects
				(font
					(size 1.27 1.27)
				)
			)
		)
		(duplicate_pad_numbers_are_jumpers no)
		(fp_line
			(start -3.400044 1.249934)
			(end 3.400044 1.249934)
			(stroke
				(width 0.1524)
				(type default)
			)
			(layer "F.SilkS")
		)
		(fp_circle
			(center 0 1.249934)
			(end 3.400044 1.249934)
			(stroke
				(width 0.1524)
				(type default)
			)
			(fill no)
			(layer "F.SilkS")
		)
		(fp_poly
			(pts
				(arc
					(start -3.400044 1.249934)
					(mid 0 4.649978)
					(end 3.400044 1.249934)
				)
			)
			(stroke
				(width 0)
				(type default)
			)
			(fill yes)
			(layer "F.SilkS")
		)
		(fp_circle
			(center 0 1.249934)
			(end 3.400044 1.249934)
			(stroke
				(width 0.1)
				(type default)
			)
			(fill no)
			(layer "F.Fab")
		)
		(pad "1" thru_hole rect
			(at 0 0)
			(size 1.524 1.524)
			(drill 1.016)
			(layers "*.Cu" "*.Mask")
			(remove_unused_layers no)
			(net "SW_P12V_PVCCINFAON_CPU0_FLT")
			(clearance 0)
			(padstack
				(mode front_inner_back)
				(layer "Inner"
					(shape circle)
					(size 1.524 1.524)
					(clearance 0)
				)
				(layer "B.Cu"
					(shape rect)
					(size 1.524 1.524)
					(clearance 0)
				)
			)
		)
		(pad "2" thru_hole circle
			(at 0 2.500122)
			(size 1.524 1.524)
			(drill 1.016)
			(layers "*.Cu" "*.Mask")
			(remove_unused_layers no)
			(net "GND")
			(clearance 0)
		)
	)
	(footprint ""
		(layer "F.Cu")
		(at 268.668246 -130.536696 180)
		(property "Reference" "U315"
			(at 1.132332 2.691892 0)
			(unlocked yes)
			(layer "F.SilkS")
			(effects
				(font
					(size 0.7874 0.5842)
					(thickness 0.1524)
				)
				(justify left)
			)
		)
		(property "Value" ""
			(at 0 0 180)
			(layer "F.Fab")
			(effects
				(font
					(size 1.27 1.27)
				)
			)
		)
		(duplicate_pad_numbers_are_jumpers no)
		(fp_line
			(start 1.463548 1.549908)
			(end -1.463548 1.549908)
			(stroke
				(width 0.1524)
				(type default)
			)
			(layer "F.SilkS")
		)
		(fp_line
			(start 1.463548 -1.549908)
			(end 1.463548 1.549908)
			(stroke
				(width 0.1524)
				(type default)
			)
			(layer "F.SilkS")
		)
		(fp_line
			(start 0.762 -1.549908)
			(end 1.463548 -1.549908)
			(stroke
				(width 0.1524)
				(type default)
			)
			(layer "F.SilkS")
		)
		(fp_line
			(start 0 -0.762)
			(end 0.762 -1.549908)
			(stroke
				(width 0.1524)
				(type default)
			)
			(layer "F.SilkS")
		)
		(fp_line
			(start -0.787908 -1.549908)
			(end 0 -0.762)
			(stroke
				(width 0.1524)
				(type default)
			)
			(layer "F.SilkS")
		)
		(fp_line
			(start -1.463548 1.549908)
			(end -1.463548 -1.549908)
			(stroke
				(width 0.1524)
				(type default)
			)
			(layer "F.SilkS")
		)
		(fp_line
			(start -1.463548 -1.549908)
			(end -0.787908 -1.549908)
			(stroke
				(width 0.1524)
				(type default)
			)
			(layer "F.SilkS")
		)
		(fp_poly
			(pts
				(xy -2.86004 -1.050036) (xy -3.4798 -0.740156) (xy -3.4798 -1.359916)
			)
			(stroke
				(width 0)
				(type default)
			)
			(fill yes)
			(layer "F.SilkS")
		)
		(fp_line
			(start 1.549908 1.549908)
			(end -1.549908 1.549908)
			(stroke
				(width 0.1)
				(type default)
			)
			(layer "F.Fab")
		)
		(fp_line
			(start 1.549908 -1.549908)
			(end 1.549908 1.549908)
			(stroke
				(width 0.1)
				(type default)
			)
			(layer "F.Fab")
		)
		(fp_line
			(start -1.549908 1.549908)
			(end -1.549908 -1.549908)
			(stroke
				(width 0.1)
				(type default)
			)
			(layer "F.Fab")
		)
		(fp_line
			(start -1.549908 -1.549908)
			(end 1.549908 -1.549908)
			(stroke
				(width 0.1)
				(type default)
			)
			(layer "F.Fab")
		)
		(fp_poly
			(pts
				(xy -3.4798 -1.359916) (xy -2.86004 -1.050036) (xy -3.4798 -0.740156)
			)
			(stroke
				(width 0)
				(type default)
			)
			(fill yes)
			(layer "F.Fab")
		)
		(pad "1" smd rect
			(at -2.175002 -1.050036 270)
			(size 0.6096 1.1684)
			(layers "F.Cu" "F.Mask" "F.Paste")
			(net "P3V3_AUX")
		)
		(pad "2" smd rect
			(at -2.175002 -0.32512 270)
			(size 0.4318 1.1684)
			(layers "F.Cu" "F.Mask" "F.Paste")
			(net "SMB_HOST_CLK_BUF_3V3AUX_SCL")
		)
		(pad "3" smd rect
			(at -2.175002 0.32512 270)
			(size 0.4318 1.1684)
			(layers "F.Cu" "F.Mask" "F.Paste")
			(net "SMB_HOST_CLK_BUF_3V3AUX_SDA")
		)
		(pad "4" smd rect
			(at -2.175002 1.050036 270)
			(size 0.6096 1.1684)
			(layers "F.Cu" "F.Mask" "F.Paste")
			(net "GND")
		)
		(pad "5" smd rect
			(at 2.175002 1.050036 270)
			(size 0.6096 1.1684)
			(layers "F.Cu" "F.Mask" "F.Paste")
			(net "PU_CLK_BUF_ISO_EN")
		)
		(pad "6" smd rect
			(at 2.175002 0.32512 270)
			(size 0.4318 1.1684)
			(layers "F.Cu" "F.Mask" "F.Paste")
			(net "SMB_HOST_CLK_BUF_ISO_3V3AUX_S_2")
		)
		(pad "7" smd rect
			(at 2.175002 -0.32512 270)
			(size 0.4318 1.1684)
			(layers "F.Cu" "F.Mask" "F.Paste")
			(net "SMB_HOST_CLK_BUF_ISO_3V3AUX_S_1")
		)
		(pad "8" smd rect
			(at 2.175002 -1.050036 270)
			(size 0.6096 1.1684)
			(layers "F.Cu" "F.Mask" "F.Paste")
			(net "P3V3")
		)
	)
	(footprint ""
		(layer "F.Cu")
		(at 131.466844 -128.516126 180)
		(property "Reference" "R2984"
			(at 0 0 180)
			(layer "F.SilkS")
			(hide yes)
			(effects
				(font
					(size 1.27 1.27)
				)
			)
		)
		(property "Value" ""
			(at 0 0 180)
			(layer "F.Fab")
			(effects
				(font
					(size 1.27 1.27)
				)
			)
		)
		(duplicate_pad_numbers_are_jumpers no)
		(fp_line
			(start 0.7874 0.4064)
			(end -0.7874 0.4064)
			(stroke
				(width 0.1524)
				(type default)
			)
			(layer "F.SilkS")
		)
		(fp_line
			(start 0.7874 -0.4064)
			(end 0.7874 0.4064)
			(stroke
				(width 0.1524)
				(type default)
			)
			(layer "F.SilkS")
		)
		(fp_line
			(start -0.7874 0.4064)
			(end -0.7874 -0.4064)
			(stroke
				(width 0.1524)
				(type default)
			)
			(layer "F.SilkS")
		)
		(fp_line
			(start -0.7874 -0.4064)
			(end 0.7874 -0.4064)
			(stroke
				(width 0.1524)
				(type default)
			)
			(layer "F.SilkS")
		)
		(fp_line
			(start 0.67945 0.3048)
			(end 0.120396 0.3048)
			(stroke
				(width 0.1)
				(type default)
			)
			(layer "F.Fab")
		)
		(fp_line
			(start 0.67945 -0.3048)
			(end 0.67945 0.3048)
			(stroke
				(width 0.1)
				(type default)
			)
			(layer "F.Fab")
		)
		(fp_line
			(start 0.12065 -0.2794)
			(end 0.12065 -0.3048)
			(stroke
				(width 0.1)
				(type default)
			)
			(layer "F.Fab")
		)
		(fp_line
			(start 0.12065 -0.3048)
			(end 0.67945 -0.3048)
			(stroke
				(width 0.1)
				(type default)
			)
			(layer "F.Fab")
		)
		(fp_line
			(start 0.120396 0.3048)
			(end 0.120396 0.2794)
			(stroke
				(width 0.1)
				(type default)
			)
			(layer "F.Fab")
		)
		(fp_line
			(start 0.120396 0.2794)
			(end -0.12065 0.2794)
			(stroke
				(width 0.1)
				(type default)
			)
			(layer "F.Fab")
		)
		(fp_line
			(start -0.12065 0.3048)
			(end -0.67945 0.3048)
			(stroke
				(width 0.1)
				(type default)
			)
			(layer "F.Fab")
		)
		(fp_line
			(start -0.12065 0.2794)
			(end -0.12065 0.3048)
			(stroke
				(width 0.1)
				(type default)
			)
			(layer "F.Fab")
		)
		(fp_line
			(start -0.12065 -0.2794)
			(end 0.12065 -0.2794)
			(stroke
				(width 0.1)
				(type default)
			)
			(layer "F.Fab")
		)
		(fp_line
			(start -0.12065 -0.305054)
			(end -0.12065 -0.2794)
			(stroke
				(width 0.1)
				(type default)
			)
			(layer "F.Fab")
		)
		(fp_line
			(start -0.67945 0.3048)
			(end -0.67945 -0.305054)
			(stroke
				(width 0.1)
				(type default)
			)
			(layer "F.Fab")
		)
		(fp_line
			(start -0.67945 -0.305054)
			(end -0.12065 -0.305054)
			(stroke
				(width 0.1)
				(type default)
			)
			(layer "F.Fab")
		)
		(pad "1" smd circle
			(at -0.40005 0 180)
			(size 0 0)
			(layers "F.Cu" "F.Mask" "F.Paste")
			(net "P3V3_AUX")
		)
		(pad "2" smd circle
			(at 0.40005 0 180)
			(size 0 0)
			(layers "F.Cu" "F.Mask" "F.Paste")
			(net "SMB_BMC_SWB_SCL")
		)
	)
)
